(kicad_pcb
	(version 20260206)
	(generator "pcbnew")
	(generator_version "10.0")
	(general
		(thickness 1.6)
		(legacy_teardrops no)
	)
	(paper "A4")
	(title_block
		(title "01162023_DA0F0TEBIF0_F0T_Expander_BD_F_brd_V02_OCP.brd")
		(comment 1 "Grand Teton / footprints 2234-2239 of 9728")
	)
	(layers
		(0 "F.Cu" signal "TOP")
		(4 "In1.Cu" signal "GND")
		(6 "In2.Cu" signal "VCC")
		(8 "In3.Cu" signal "VCC1")
		(10 "In4.Cu" signal "GND1")
		(12 "In5.Cu" signal "IN1")
		(14 "In6.Cu" signal "GND2")
		(16 "In7.Cu" signal "IN2")
		(18 "In8.Cu" signal "GND3")
		(20 "In9.Cu" signal "IN3")
		(22 "In10.Cu" signal "GND4")
		(24 "In11.Cu" signal "IN4")
		(26 "In12.Cu" signal "GND5")
		(28 "In13.Cu" signal "IN5")
		(30 "In14.Cu" signal "GND6")
		(32 "In15.Cu" signal "IN6")
		(34 "In16.Cu" signal "GND7")
		(2 "B.Cu" signal "BOTTOM")
		(9 "F.Adhes" user "F.Adhesive")
		(11 "B.Adhes" user "B.Adhesive")
		(13 "F.Paste" user "Package Geometry/Pastemask Top")
		(15 "B.Paste" user "Package Geometry/Pastemask Bottom")
		(5 "F.SilkS" user "Ref Des/Silkscreen Top")
		(7 "B.SilkS" user "Ref Des/Silkscreen Bottom")
		(1 "F.Mask" user "Board Geometry/Soldermask Top")
		(3 "B.Mask" user "Board Geometry/Soldermask Bottom")
		(17 "Dwgs.User" user "User.Drawings")
		(19 "Cmts.User" user "User.Comments")
		(21 "Eco1.User" user "User.Eco1")
		(23 "Eco2.User" user "User.Eco2")
		(25 "Edge.Cuts" user "Board Geometry/Outline")
		(27 "Margin" user)
		(31 "F.CrtYd" user "Package Geometry/Place Bound Top")
		(29 "B.CrtYd" user "Package Geometry/Place Bound Bottom")
		(35 "F.Fab" user "Ref Des/Assembly Top")
		(33 "B.Fab" user "Ref Des/Assembly Bottom")
	)
	(footprint ""
		(layer "F.Cu")
		(at 194.343782 -47.92091)
		(property "Reference" "R570"
			(at 0 0 0)
			(layer "F.SilkS")
			(hide yes)
			(effects
				(font
					(size 1.27 1.27)
				)
			)
		)
		(property "Value" ""
			(at 0 0 0)
			(layer "F.Fab")
			(effects
				(font
					(size 1.27 1.27)
				)
			)
		)
		(duplicate_pad_numbers_are_jumpers no)
		(fp_line
			(start -0.7874 -0.4064)
			(end 0.7874 -0.4064)
			(stroke
				(width 0.1524)
				(type default)
			)
			(layer "F.SilkS")
		)
		(fp_line
			(start -0.7874 0.4064)
			(end -0.7874 -0.4064)
			(stroke
				(width 0.1524)
				(type default)
			)
			(layer "F.SilkS")
		)
		(fp_line
			(start 0.7874 -0.4064)
			(end 0.7874 0.4064)
			(stroke
				(width 0.1524)
				(type default)
			)
			(layer "F.SilkS")
		)
		(fp_line
			(start 0.7874 0.4064)
			(end -0.7874 0.4064)
			(stroke
				(width 0.1524)
				(type default)
			)
			(layer "F.SilkS")
		)
		(fp_line
			(start -0.67945 -0.305054)
			(end -0.12065 -0.305054)
			(stroke
				(width 0.1)
				(type default)
			)
			(layer "F.Fab")
		)
		(fp_line
			(start -0.67945 0.3048)
			(end -0.67945 -0.305054)
			(stroke
				(width 0.1)
				(type default)
			)
			(layer "F.Fab")
		)
		(fp_line
			(start -0.12065 -0.305054)
			(end -0.12065 -0.2794)
			(stroke
				(width 0.1)
				(type default)
			)
			(layer "F.Fab")
		)
		(fp_line
			(start -0.12065 -0.2794)
			(end 0.12065 -0.2794)
			(stroke
				(width 0.1)
				(type default)
			)
			(layer "F.Fab")
		)
		(fp_line
			(start -0.12065 0.2794)
			(end -0.12065 0.3048)
			(stroke
				(width 0.1)
				(type default)
			)
			(layer "F.Fab")
		)
		(fp_line
			(start -0.12065 0.3048)
			(end -0.67945 0.3048)
			(stroke
				(width 0.1)
				(type default)
			)
			(layer "F.Fab")
		)
		(fp_line
			(start 0.120396 0.2794)
			(end -0.12065 0.2794)
			(stroke
				(width 0.1)
				(type default)
			)
			(layer "F.Fab")
		)
		(fp_line
			(start 0.120396 0.3048)
			(end 0.120396 0.2794)
			(stroke
				(width 0.1)
				(type default)
			)
			(layer "F.Fab")
		)
		(fp_line
			(start 0.12065 -0.3048)
			(end 0.67945 -0.3048)
			(stroke
				(width 0.1)
				(type default)
			)
			(layer "F.Fab")
		)
		(fp_line
			(start 0.12065 -0.2794)
			(end 0.12065 -0.3048)
			(stroke
				(width 0.1)
				(type default)
			)
			(layer "F.Fab")
		)
		(fp_line
			(start 0.67945 -0.3048)
			(end 0.67945 0.3048)
			(stroke
				(width 0.1)
				(type default)
			)
			(layer "F.Fab")
		)
		(fp_line
			(start 0.67945 0.3048)
			(end 0.120396 0.3048)
			(stroke
				(width 0.1)
				(type default)
			)
			(layer "F.Fab")
		)
		(pad "1" smd circle
			(at -0.40005 0)
			(size 0 0)
			(layers "F.Cu" "F.Mask" "F.Paste")
			(net "P3V3_AUX")
		)
		(pad "2" smd circle
			(at 0.40005 0)
			(size 0 0)
			(layers "F.Cu" "F.Mask" "F.Paste")
			(net "SSD_0_7_ADC_ALERT_N")
		)
	)
	(footprint ""
		(layer "F.Cu")
		(at 32.411416 -296.445432 -90)
		(property "Reference" "R4558"
			(at 0 0 270)
			(layer "F.SilkS")
			(hide yes)
			(effects
				(font
					(size 1.27 1.27)
				)
			)
		)
		(property "Value" ""
			(at 0 0 270)
			(layer "F.Fab")
			(effects
				(font
					(size 1.27 1.27)
				)
			)
		)
		(duplicate_pad_numbers_are_jumpers no)
		(fp_line
			(start -0.7874 0.4064)
			(end -0.7874 -0.4064)
			(stroke
				(width 0.1524)
				(type default)
			)
			(layer "F.SilkS")
		)
		(fp_line
			(start 0.7874 0.4064)
			(end -0.7874 0.4064)
			(stroke
				(width 0.1524)
				(type default)
			)
			(layer "F.SilkS")
		)
		(fp_line
			(start -0.7874 -0.4064)
			(end 0.7874 -0.4064)
			(stroke
				(width 0.1524)
				(type default)
			)
			(layer "F.SilkS")
		)
		(fp_line
			(start 0.7874 -0.4064)
			(end 0.7874 0.4064)
			(stroke
				(width 0.1524)
				(type default)
			)
			(layer "F.SilkS")
		)
		(fp_line
			(start -0.67945 0.3048)
			(end -0.67945 -0.305054)
			(stroke
				(width 0.1)
				(type default)
			)
			(layer "F.Fab")
		)
		(fp_line
			(start -0.12065 0.3048)
			(end -0.67945 0.3048)
			(stroke
				(width 0.1)
				(type default)
			)
			(layer "F.Fab")
		)
		(fp_line
			(start 0.120396 0.3048)
			(end 0.120396 0.2794)
			(stroke
				(width 0.1)
				(type default)
			)
			(layer "F.Fab")
		)
		(fp_line
			(start 0.67945 0.3048)
			(end 0.120396 0.3048)
			(stroke
				(width 0.1)
				(type default)
			)
			(layer "F.Fab")
		)
		(fp_line
			(start -0.12065 0.2794)
			(end -0.12065 0.3048)
			(stroke
				(width 0.1)
				(type default)
			)
			(layer "F.Fab")
		)
		(fp_line
			(start 0.120396 0.2794)
			(end -0.12065 0.2794)
			(stroke
				(width 0.1)
				(type default)
			)
			(layer "F.Fab")
		)
		(fp_line
			(start -0.12065 -0.2794)
			(end 0.12065 -0.2794)
			(stroke
				(width 0.1)
				(type default)
			)
			(layer "F.Fab")
		)
		(fp_line
			(start 0.12065 -0.2794)
			(end 0.12065 -0.3048)
			(stroke
				(width 0.1)
				(type default)
			)
			(layer "F.Fab")
		)
		(fp_line
			(start 0.12065 -0.3048)
			(end 0.67945 -0.3048)
			(stroke
				(width 0.1)
				(type default)
			)
			(layer "F.Fab")
		)
		(fp_line
			(start 0.67945 -0.3048)
			(end 0.67945 0.3048)
			(stroke
				(width 0.1)
				(type default)
			)
			(layer "F.Fab")
		)
		(fp_line
			(start -0.67945 -0.305054)
			(end -0.12065 -0.305054)
			(stroke
				(width 0.1)
				(type default)
			)
			(layer "F.Fab")
		)
		(fp_line
			(start -0.12065 -0.305054)
			(end -0.12065 -0.2794)
			(stroke
				(width 0.1)
				(type default)
			)
			(layer "F.Fab")
		)
		(pad "1" smd circle
			(at -0.40005 0 270)
			(size 0 0)
			(layers "F.Cu" "F.Mask" "F.Paste")
			(net "PCEPLL0_VDDA18_PEX0")
		)
		(pad "2" smd circle
			(at 0.40005 0 270)
			(size 0 0)
			(layers "F.Cu" "F.Mask" "F.Paste")
			(net "PCEPLL0_VDDA18_PEX0_R")
		)
	)
	(footprint ""
		(layer "F.Cu")
		(at 38.608 -163.061396 180)
		(property "Reference" "R4"
			(at 0 0 180)
			(layer "F.SilkS")
			(hide yes)
			(effects
				(font
					(size 1.27 1.27)
				)
			)
		)
		(property "Value" ""
			(at 0 0 180)
			(layer "F.Fab")
			(effects
				(font
					(size 1.27 1.27)
				)
			)
		)
		(duplicate_pad_numbers_are_jumpers no)
		(fp_line
			(start 0.7874 0.4064)
			(end -0.7874 0.4064)
			(stroke
				(width 0.1524)
				(type default)
			)
			(layer "F.SilkS")
		)
		(fp_line
			(start 0.7874 -0.4064)
			(end 0.7874 0.4064)
			(stroke
				(width 0.1524)
				(type default)
			)
			(layer "F.SilkS")
		)
		(fp_line
			(start -0.7874 0.4064)
			(end -0.7874 -0.4064)
			(stroke
				(width 0.1524)
				(type default)
			)
			(layer "F.SilkS")
		)
		(fp_line
			(start -0.7874 -0.4064)
			(end 0.7874 -0.4064)
			(stroke
				(width 0.1524)
				(type default)
			)
			(layer "F.SilkS")
		)
		(fp_line
			(start 0.67945 0.3048)
			(end 0.120396 0.3048)
			(stroke
				(width 0.1)
				(type default)
			)
			(layer "F.Fab")
		)
		(fp_line
			(start 0.67945 -0.3048)
			(end 0.67945 0.3048)
			(stroke
				(width 0.1)
				(type default)
			)
			(layer "F.Fab")
		)
		(fp_line
			(start 0.12065 -0.2794)
			(end 0.12065 -0.3048)
			(stroke
				(width 0.1)
				(type default)
			)
			(layer "F.Fab")
		)
		(fp_line
			(start 0.12065 -0.3048)
			(end 0.67945 -0.3048)
			(stroke
				(width 0.1)
				(type default)
			)
			(layer "F.Fab")
		)
		(fp_line
			(start 0.120396 0.3048)
			(end 0.120396 0.2794)
			(stroke
				(width 0.1)
				(type default)
			)
			(layer "F.Fab")
		)
		(fp_line
			(start 0.120396 0.2794)
			(end -0.12065 0.2794)
			(stroke
				(width 0.1)
				(type default)
			)
			(layer "F.Fab")
		)
		(fp_line
			(start -0.12065 0.3048)
			(end -0.67945 0.3048)
			(stroke
				(width 0.1)
				(type default)
			)
			(layer "F.Fab")
		)
		(fp_line
			(start -0.12065 0.2794)
			(end -0.12065 0.3048)
			(stroke
				(width 0.1)
				(type default)
			)
			(layer "F.Fab")
		)
		(fp_line
			(start -0.12065 -0.2794)
			(end 0.12065 -0.2794)
			(stroke
				(width 0.1)
				(type default)
			)
			(layer "F.Fab")
		)
		(fp_line
			(start -0.12065 -0.305054)
			(end -0.12065 -0.2794)
			(stroke
				(width 0.1)
				(type default)
			)
			(layer "F.Fab")
		)
		(fp_line
			(start -0.67945 0.3048)
			(end -0.67945 -0.305054)
			(stroke
				(width 0.1)
				(type default)
			)
			(layer "F.Fab")
		)
		(fp_line
			(start -0.67945 -0.305054)
			(end -0.12065 -0.305054)
			(stroke
				(width 0.1)
				(type default)
			)
			(layer "F.Fab")
		)
		(pad "1" smd circle
			(at -0.40005 0 180)
			(size 0 0)
			(layers "F.Cu" "F.Mask" "F.Paste")
			(net "PWRGD_NIC0_PWR_GOOD")
		)
		(pad "2" smd circle
			(at 0.40005 0 180)
			(size 0 0)
			(layers "F.Cu" "F.Mask" "F.Paste")
			(net "PWRGD_NIC0_PWR_GOOD_R")
		)
	)
	(footprint ""
		(layer "F.Cu")
		(at 92.352622 -311.197244 135)
		(property "Reference" "R1246"
			(at 0 0 135)
			(layer "F.SilkS")
			(hide yes)
			(effects
				(font
					(size 1.27 1.27)
				)
			)
		)
		(property "Value" ""
			(at 0 0 135)
			(layer "F.Fab")
			(effects
				(font
					(size 1.27 1.27)
				)
			)
		)
		(duplicate_pad_numbers_are_jumpers no)
		(fp_line
			(start 0.787389 -0.406267)
			(end 0.787389 0.406267)
			(stroke
				(width 0.1524)
				(type default)
			)
			(layer "F.SilkS")
		)
		(fp_line
			(start 0.787389 0.406267)
			(end -0.787389 0.406267)
			(stroke
				(width 0.1524)
				(type default)
			)
			(layer "F.SilkS")
		)
		(fp_line
			(start -0.787389 -0.406267)
			(end 0.787389 -0.406267)
			(stroke
				(width 0.1524)
				(type default)
			)
			(layer "F.SilkS")
		)
		(fp_line
			(start -0.787389 0.406267)
			(end -0.787389 -0.406267)
			(stroke
				(width 0.1524)
				(type default)
			)
			(layer "F.SilkS")
		)
		(fp_line
			(start 0.679446 -0.30479)
			(end 0.679446 0.30479)
			(stroke
				(width 0.1)
				(type default)
			)
			(layer "F.Fab")
		)
		(fp_line
			(start 0.120515 -0.30479)
			(end 0.679446 -0.30479)
			(stroke
				(width 0.1)
				(type default)
			)
			(layer "F.Fab")
		)
		(fp_line
			(start 0.120695 -0.279466)
			(end 0.120515 -0.30479)
			(stroke
				(width 0.1)
				(type default)
			)
			(layer "F.Fab")
		)
		(fp_line
			(start 0.679446 0.30479)
			(end 0.120515 0.30479)
			(stroke
				(width 0.1)
				(type default)
			)
			(layer "F.Fab")
		)
		(fp_line
			(start -0.120695 -0.304969)
			(end -0.120695 -0.279466)
			(stroke
				(width 0.1)
				(type default)
			)
			(layer "F.Fab")
		)
		(fp_line
			(start -0.120695 -0.279466)
			(end 0.120695 -0.279466)
			(stroke
				(width 0.1)
				(type default)
			)
			(layer "F.Fab")
		)
		(fp_line
			(start 0.120335 0.279466)
			(end -0.120695 0.279466)
			(stroke
				(width 0.1)
				(type default)
			)
			(layer "F.Fab")
		)
		(fp_line
			(start 0.120515 0.30479)
			(end 0.120335 0.279466)
			(stroke
				(width 0.1)
				(type default)
			)
			(layer "F.Fab")
		)
		(fp_line
			(start -0.679446 -0.305149)
			(end -0.120695 -0.304969)
			(stroke
				(width 0.1)
				(type default)
			)
			(layer "F.Fab")
		)
		(fp_line
			(start -0.120695 0.279466)
			(end -0.120515 0.30479)
			(stroke
				(width 0.1)
				(type default)
			)
			(layer "F.Fab")
		)
		(fp_line
			(start -0.120515 0.30479)
			(end -0.679446 0.30479)
			(stroke
				(width 0.1)
				(type default)
			)
			(layer "F.Fab")
		)
		(fp_line
			(start -0.679446 0.30479)
			(end -0.679446 -0.305149)
			(stroke
				(width 0.1)
				(type default)
			)
			(layer "F.Fab")
		)
		(pad "1" smd circle
			(at -0.40005 0 135)
			(size 0 0)
			(layers "F.Cu" "F.Mask" "F.Paste")
			(net "GND")
		)
		(pad "2" smd circle
			(at 0.40005 0 135)
			(size 0 0)
			(layers "F.Cu" "F.Mask" "F.Paste")
			(net "PEX0_SPARE5")
		)
	)
	(footprint ""
		(layer "F.Cu")
		(at 338.074 -149.987 180)
		(property "Reference" "R4844"
			(at 0 0 180)
			(layer "F.SilkS")
			(hide yes)
			(effects
				(font
					(size 1.27 1.27)
				)
			)
		)
		(property "Value" ""
			(at 0 0 180)
			(layer "F.Fab")
			(effects
				(font
					(size 1.27 1.27)
				)
			)
		)
		(duplicate_pad_numbers_are_jumpers no)
		(fp_line
			(start 0.7874 0.4064)
			(end -0.7874 0.4064)
			(stroke
				(width 0.1524)
				(type default)
			)
			(layer "F.SilkS")
		)
		(fp_line
			(start 0.7874 -0.4064)
			(end 0.7874 0.4064)
			(stroke
				(width 0.1524)
				(type default)
			)
			(layer "F.SilkS")
		)
		(fp_line
			(start -0.7874 0.4064)
			(end -0.7874 -0.4064)
			(stroke
				(width 0.1524)
				(type default)
			)
			(layer "F.SilkS")
		)
		(fp_line
			(start -0.7874 -0.4064)
			(end 0.7874 -0.4064)
			(stroke
				(width 0.1524)
				(type default)
			)
			(layer "F.SilkS")
		)
		(fp_line
			(start 0.67945 0.3048)
			(end 0.120396 0.3048)
			(stroke
				(width 0.1)
				(type default)
			)
			(layer "F.Fab")
		)
		(fp_line
			(start 0.67945 -0.3048)
			(end 0.67945 0.3048)
			(stroke
				(width 0.1)
				(type default)
			)
			(layer "F.Fab")
		)
		(fp_line
			(start 0.12065 -0.2794)
			(end 0.12065 -0.3048)
			(stroke
				(width 0.1)
				(type default)
			)
			(layer "F.Fab")
		)
		(fp_line
			(start 0.12065 -0.3048)
			(end 0.67945 -0.3048)
			(stroke
				(width 0.1)
				(type default)
			)
			(layer "F.Fab")
		)
		(fp_line
			(start 0.120396 0.3048)
			(end 0.120396 0.2794)
			(stroke
				(width 0.1)
				(type default)
			)
			(layer "F.Fab")
		)
		(fp_line
			(start 0.120396 0.2794)
			(end -0.12065 0.2794)
			(stroke
				(width 0.1)
				(type default)
			)
			(layer "F.Fab")
		)
		(fp_line
			(start -0.12065 0.3048)
			(end -0.67945 0.3048)
			(stroke
				(width 0.1)
				(type default)
			)
			(layer "F.Fab")
		)
		(fp_line
			(start -0.12065 0.2794)
			(end -0.12065 0.3048)
			(stroke
				(width 0.1)
				(type default)
			)
			(layer "F.Fab")
		)
		(fp_line
			(start -0.12065 -0.2794)
			(end 0.12065 -0.2794)
			(stroke
				(width 0.1)
				(type default)
			)
			(layer "F.Fab")
		)
		(fp_line
			(start -0.12065 -0.305054)
			(end -0.12065 -0.2794)
			(stroke
				(width 0.1)
				(type default)
			)
			(layer "F.Fab")
		)
		(fp_line
			(start -0.67945 0.3048)
			(end -0.67945 -0.305054)
			(stroke
				(width 0.1)
				(type default)
			)
			(layer "F.Fab")
		)
		(fp_line
			(start -0.67945 -0.305054)
			(end -0.12065 -0.305054)
			(stroke
				(width 0.1)
				(type default)
			)
			(layer "F.Fab")
		)
		(pad "1" smd circle
			(at -0.40005 0 180)
			(size 0 0)
			(layers "F.Cu" "F.Mask" "F.Paste")
			(net "GND")
		)
		(pad "2" smd circle
			(at 0.40005 0 180)
			(size 0 0)
			(layers "F.Cu" "F.Mask" "F.Paste")
			(net "PCA9555_1_PEX3_A1")
		)
	)
	(footprint ""
		(layer "F.Cu")
		(at 115.727226 -318.51473 90)
		(property "Reference" "R6459"
			(at 0 0 90)
			(layer "F.SilkS")
			(hide yes)
			(effects
				(font
					(size 1.27 1.27)
				)
			)
		)
		(property "Value" ""
			(at 0 0 90)
			(layer "F.Fab")
			(effects
				(font
					(size 1.27 1.27)
				)
			)
		)
		(duplicate_pad_numbers_are_jumpers no)
		(fp_line
			(start 0.7874 -0.4064)
			(end 0.7874 0.4064)
			(stroke
				(width 0.1524)
				(type default)
			)
			(layer "F.SilkS")
		)
		(fp_line
			(start -0.7874 -0.4064)
			(end 0.7874 -0.4064)
			(stroke
				(width 0.1524)
				(type default)
			)
			(layer "F.SilkS")
		)
		(fp_line
			(start 0.7874 0.4064)
			(end -0.7874 0.4064)
			(stroke
				(width 0.1524)
				(type default)
			)
			(layer "F.SilkS")
		)
		(fp_line
			(start -0.7874 0.4064)
			(end -0.7874 -0.4064)
			(stroke
				(width 0.1524)
				(type default)
			)
			(layer "F.SilkS")
		)
		(fp_line
			(start -0.12065 -0.305054)
			(end -0.12065 -0.2794)
			(stroke
				(width 0.1)
				(type default)
			)
			(layer "F.Fab")
		)
		(fp_line
			(start -0.67945 -0.305054)
			(end -0.12065 -0.305054)
			(stroke
				(width 0.1)
				(type default)
			)
			(layer "F.Fab")
		)
		(fp_line
			(start 0.67945 -0.3048)
			(end 0.67945 0.3048)
			(stroke
				(width 0.1)
				(type default)
			)
			(layer "F.Fab")
		)
		(fp_line
			(start 0.12065 -0.3048)
			(end 0.67945 -0.3048)
			(stroke
				(width 0.1)
				(type default)
			)
			(layer "F.Fab")
		)
		(fp_line
			(start 0.12065 -0.2794)
			(end 0.12065 -0.3048)
			(stroke
				(width 0.1)
				(type default)
			)
			(layer "F.Fab")
		)
		(fp_line
			(start -0.12065 -0.2794)
			(end 0.12065 -0.2794)
			(stroke
				(width 0.1)
				(type default)
			)
			(layer "F.Fab")
		)
		(fp_line
			(start 0.120396 0.2794)
			(end -0.12065 0.2794)
			(stroke
				(width 0.1)
				(type default)
			)
			(layer "F.Fab")
		)
		(fp_line
			(start -0.12065 0.2794)
			(end -0.12065 0.3048)
			(stroke
				(width 0.1)
				(type default)
			)
			(layer "F.Fab")
		)
		(fp_line
			(start 0.67945 0.3048)
			(end 0.120396 0.3048)
			(stroke
				(width 0.1)
				(type default)
			)
			(layer "F.Fab")
		)
		(fp_line
			(start 0.120396 0.3048)
			(end 0.120396 0.2794)
			(stroke
				(width 0.1)
				(type default)
			)
			(layer "F.Fab")
		)
		(fp_line
			(start -0.12065 0.3048)
			(end -0.67945 0.3048)
			(stroke
				(width 0.1)
				(type default)
			)
			(layer "F.Fab")
		)
		(fp_line
			(start -0.67945 0.3048)
			(end -0.67945 -0.305054)
			(stroke
				(width 0.1)
				(type default)
			)
			(layer "F.Fab")
		)
		(pad "1" smd circle
			(at -0.40005 0 90)
			(size 0 0)
			(layers "F.Cu" "F.Mask" "F.Paste")
			(net "P0V8_SERDES_VDDA_PEX0")
		)
		(pad "2" smd circle
			(at 0.40005 0 90)
			(size 0 0)
			(layers "F.Cu" "F.Mask" "F.Paste")
			(net "P0V8_SERDES_VDDA_PEX0_C10")
		)
	)
)
